# SCM (Grand Teton) — schematic netlist excerpt (pin names and nets, part order shuffled) for the footprints in the layout excerpt that follows; sources: Cadence DE-HDL packaged netlist, KiCad conversion of 12092022_DA0F0TMDCD0_F0T_Management_Board_D_brd_V3_OCP.brd

R154  Q_RES  0 5% EMPTY  pkg 0402LF  page 13 : A = P1V8_AUX ; B = P3V3_P2V5_P1V8_RVDD
C20  Q_CAP  0.1UF 25V 10% X7R  pkg 0402  page 30 : A = P3V3_AUX ; B = GND

(kicad_pcb
	(version 20260206)
	(generator "pcbnew")
	(generator_version "10.0")
	(general
		(thickness 1.6)
		(legacy_teardrops no)
	)
	(paper "A4")
	(title_block
		(title "12092022_DA0F0TMDCD0_F0T_Management_Board_D_brd_V3_OCP.brd")
		(comment 1 "Grand Teton / footprints 334-335 of 1440")
	)
	(layers
		(0 "F.Cu" signal "TOP")
		(4 "In1.Cu" signal "GND")
		(6 "In2.Cu" signal "IN1")
		(8 "In3.Cu" signal "GND1")
		(10 "In4.Cu" signal "IN2")
		(12 "In5.Cu" signal "VCC")
		(14 "In6.Cu" signal "VCC1")
		(16 "In7.Cu" signal "IN3")
		(18 "In8.Cu" signal "GND2")
		(20 "In9.Cu" signal "IN4")
		(22 "In10.Cu" signal "GND3")
		(2 "B.Cu" signal "BOTTOM")
		(9 "F.Adhes" user "F.Adhesive")
		(11 "B.Adhes" user "B.Adhesive")
		(13 "F.Paste" user "Package Geometry/Pastemask Top")
		(15 "B.Paste" user "Package Geometry/Pastemask Bottom")
		(5 "F.SilkS" user "Ref Des/Silkscreen Top")
		(7 "B.SilkS" user "Ref Des/Silkscreen Bottom")
		(1 "F.Mask" user "Board Geometry/Soldermask Top")
		(3 "B.Mask" user "Board Geometry/Soldermask Bottom")
		(17 "Dwgs.User" user "User.Drawings")
		(19 "Cmts.User" user "User.Comments")
		(21 "Eco1.User" user "User.Eco1")
		(23 "Eco2.User" user "User.Eco2")
		(25 "Edge.Cuts" user "Board Geometry/Outline")
		(27 "Margin" user)
		(31 "F.CrtYd" user "Package Geometry/Place Bound Top")
		(29 "B.CrtYd" user "Package Geometry/Place Bound Bottom")
		(35 "F.Fab" user "Ref Des/Assembly Top")
		(33 "B.Fab" user "Ref Des/Assembly Bottom")
	)
	(footprint ""
		(layer "F.Cu")
		(at 18.415 -66.04 90)
		(property "Reference" "C20"
			(at 0 0 90)
			(layer "F.SilkS")
			(hide yes)
			(effects
				(font
					(size 1.27 1.27)
				)
			)
		)
		(property "Value" ""
			(at 0 0 90)
			(layer "F.Fab")
			(effects
				(font
					(size 1.27 1.27)
				)
			)
		)
		(duplicate_pad_numbers_are_jumpers no)
		(fp_line
			(start 0.7874 -0.4064)
			(end 0.7874 0.4064)
			(stroke
				(width 0.1524)
				(type default)
			)
			(layer "F.SilkS")
		)
		(fp_line
			(start -0.7874 -0.4064)
			(end 0.7874 -0.4064)
			(stroke
				(width 0.1524)
				(type default)
			)
			(layer "F.SilkS")
		)
		(fp_line
			(start 0.7874 0.4064)
			(end -0.7874 0.4064)
			(stroke
				(width 0.1524)
				(type default)
			)
			(layer "F.SilkS")
		)
		(fp_line
			(start -0.7874 0.4064)
			(end -0.7874 -0.4064)
			(stroke
				(width 0.1524)
				(type default)
			)
			(layer "F.SilkS")
		)
		(fp_line
			(start -0.12065 -0.305054)
			(end -0.12065 -0.2794)
			(stroke
				(width 0.1)
				(type default)
			)
			(layer "F.Fab")
		)
		(fp_line
			(start -0.67945 -0.305054)
			(end -0.12065 -0.305054)
			(stroke
				(width 0.1)
				(type default)
			)
			(layer "F.Fab")
		)
		(fp_line
			(start 0.67945 -0.3048)
			(end 0.67945 0.3048)
			(stroke
				(width 0.1)
				(type default)
			)
			(layer "F.Fab")
		)
		(fp_line
			(start 0.12065 -0.3048)
			(end 0.67945 -0.3048)
			(stroke
				(width 0.1)
				(type default)
			)
			(layer "F.Fab")
		)
		(fp_line
			(start 0.12065 -0.2794)
			(end 0.12065 -0.3048)
			(stroke
				(width 0.1)
				(type default)
			)
			(layer "F.Fab")
		)
		(fp_line
			(start -0.12065 -0.2794)
			(end 0.12065 -0.2794)
			(stroke
				(width 0.1)
				(type default)
			)
			(layer "F.Fab")
		)
		(fp_line
			(start 0.120396 0.2794)
			(end -0.12065 0.2794)
			(stroke
				(width 0.1)
				(type default)
			)
			(layer "F.Fab")
		)
		(fp_line
			(start -0.12065 0.2794)
			(end -0.12065 0.3048)
			(stroke
				(width 0.1)
				(type default)
			)
			(layer "F.Fab")
		)
		(fp_line
			(start 0.67945 0.3048)
			(end 0.120396 0.3048)
			(stroke
				(width 0.1)
				(type default)
			)
			(layer "F.Fab")
		)
		(fp_line
			(start 0.120396 0.3048)
			(end 0.120396 0.2794)
			(stroke
				(width 0.1)
				(type default)
			)
			(layer "F.Fab")
		)
		(fp_line
			(start -0.12065 0.3048)
			(end -0.67945 0.3048)
			(stroke
				(width 0.1)
				(type default)
			)
			(layer "F.Fab")
		)
		(fp_line
			(start -0.67945 0.3048)
			(end -0.67945 -0.305054)
			(stroke
				(width 0.1)
				(type default)
			)
			(layer "F.Fab")
		)
		(pad "1" smd circle
			(at -0.40005 0 90)
			(size 0 0)
			(layers "F.Cu" "F.Mask" "F.Paste")
			(net "P3V3_AUX")
		)
		(pad "2" smd circle
			(at 0.40005 0 90)
			(size 0 0)
			(layers "F.Cu" "F.Mask" "F.Paste")
			(net "GND")
		)
	)
	(footprint ""
		(layer "F.Cu")
		(at 39.73322 -36.571174 90)
		(property "Reference" "R154"
			(at 0 0 90)
			(layer "F.SilkS")
			(hide yes)
			(effects
				(font
					(size 1.27 1.27)
				)
			)
		)
		(property "Value" ""
			(at 0 0 90)
			(layer "F.Fab")
			(effects
				(font
					(size 1.27 1.27)
				)
			)
		)
		(duplicate_pad_numbers_are_jumpers no)
		(fp_line
			(start 0.7874 -0.4064)
			(end 0.7874 0.4064)
			(stroke
				(width 0.1524)
				(type default)
			)
			(layer "F.SilkS")
		)
		(fp_line
			(start -0.7874 -0.4064)
			(end 0.7874 -0.4064)
			(stroke
				(width 0.1524)
				(type default)
			)
			(layer "F.SilkS")
		)
		(fp_line
			(start 0.7874 0.4064)
			(end -0.7874 0.4064)
			(stroke
				(width 0.1524)
				(type default)
			)
			(layer "F.SilkS")
		)
		(fp_line
			(start -0.7874 0.4064)
			(end -0.7874 -0.4064)
			(stroke
				(width 0.1524)
				(type default)
			)
			(layer "F.SilkS")
		)
		(fp_line
			(start -0.12065 -0.305054)
			(end -0.12065 -0.2794)
			(stroke
				(width 0.1)
				(type default)
			)
			(layer "F.Fab")
		)
		(fp_line
			(start -0.67945 -0.305054)
			(end -0.12065 -0.305054)
			(stroke
				(width 0.1)
				(type default)
			)
			(layer "F.Fab")
		)
		(fp_line
			(start 0.67945 -0.3048)
			(end 0.67945 0.3048)
			(stroke
				(width 0.1)
				(type default)
			)
			(layer "F.Fab")
		)
		(fp_line
			(start 0.12065 -0.3048)
			(end 0.67945 -0.3048)
			(stroke
				(width 0.1)
				(type default)
			)
			(layer "F.Fab")
		)
		(fp_line
			(start 0.12065 -0.2794)
			(end 0.12065 -0.3048)
			(stroke
				(width 0.1)
				(type default)
			)
			(layer "F.Fab")
		)
		(fp_line
			(start -0.12065 -0.2794)
			(end 0.12065 -0.2794)
			(stroke
				(width 0.1)
				(type default)
			)
			(layer "F.Fab")
		)
		(fp_line
			(start 0.120396 0.2794)
			(end -0.12065 0.2794)
			(stroke
				(width 0.1)
				(type default)
			)
			(layer "F.Fab")
		)
		(fp_line
			(start -0.12065 0.2794)
			(end -0.12065 0.3048)
			(stroke
				(width 0.1)
				(type default)
			)
			(layer "F.Fab")
		)
		(fp_line
			(start 0.67945 0.3048)
			(end 0.120396 0.3048)
			(stroke
				(width 0.1)
				(type default)
			)
			(layer "F.Fab")
		)
		(fp_line
			(start 0.120396 0.3048)
			(end 0.120396 0.2794)
			(stroke
				(width 0.1)
				(type default)
			)
			(layer "F.Fab")
		)
		(fp_line
			(start -0.12065 0.3048)
			(end -0.67945 0.3048)
			(stroke
				(width 0.1)
				(type default)
			)
			(layer "F.Fab")
		)
		(fp_line
			(start -0.67945 0.3048)
			(end -0.67945 -0.305054)
			(stroke
				(width 0.1)
				(type default)
			)
			(layer "F.Fab")
		)
		(pad "1" smd circle
			(at -0.40005 0 90)
			(size 0 0)
			(layers "F.Cu" "F.Mask" "F.Paste")
			(net "P1V8_AUX")
		)
		(pad "2" smd circle
			(at 0.40005 0 90)
			(size 0 0)
			(layers "F.Cu" "F.Mask" "F.Paste")
			(net "P3V3_P2V5_P1V8_RVDD")
		)
	)
)
